FILE_TYPE = MACRO_DRAWING;
SET COLOR_WIRE YELLOW;
SET COLOR_PROP ORANGE;
SET COLOR_DOT WHITE;
SET COLOR_ARC YELLOW;
SET COLOR_BODY GREEN;
SET COLOR_NOTE PURPLE;
SET PROP_DISPLAY VALUE;
SET PAGE_NUMBER P412;
FORCEADD QUANTA_TITLE_BLOCK_C..1
(0 0);
FORCEPROP 1 LAST CUSTOM_TXT_CDS <NAME_2>
J 0
(-3175 50);
FORCEPROP 1 LAST CUSTOM_TXT_CDS <NAME_1>
J 0
(-3175 175);
FORCEPROP 1 LAST CUSTOM_TXT_CDS <Q_NUMBER>
J 0
(-1403 103);
DISPLAY 1.212766 (-1403 103);
FORCEPROP 1 LAST CUSTOM_TXT_CDS <Q_PROJ>
J 0
(-2382 102);
DISPLAY 1.212766 (-2382 102);
FORCEPROP 1 LAST CUSTOM_TXT_CDS <Q_REV>
J 0
(-184 103);
DISPLAY 1.212766 (-184 103);
FORCEPROP 1 LAST CUSTOM_TXT_CDS <CON_LAST_MODIFIED>
J 0
(-1885 15);
DISPLAY 0.978723 (-1885 15);
FORCEPROP 1 LAST CUSTOM_TXT_CDS <CON_PAGE_NUM> OF <CON_TOTAL_PAGES>
J 0
(-446 18);
DISPLAY 0.978723 (-446 18);
FORCEPROP 1 LAST Q_TITLE RETIMER_CPU0_P1(9)
J 0
(-9366 26);
DISPLAY 2.446809 (-9366 26);
PAINT GREEN (-9366 26);
FORCEPROP 2 LAST CDS_LIB pure_quanta
J 0
(0 0);
DISPLAY INVISIBLE (0 0);
FORCEPROP 1 LAST CDS_LMAN_SYM_OUTLINE -9475,6775,100,-125
J 0
(0 0);
DISPLAY 0.468085 (0 0);
PAINT GREEN (0 0);
DISPLAY INVISIBLE (0 0);
FORCEPROP 2 LAST PAGE_BORDER TRUE
J 0
(-7890 5250);
DISPLAY 0.638298 (-7890 5250);
PAINT PINK (-7890 5250);
DISPLAY INVISIBLE (-7890 5250);
FORCEPROP 2 LAST CDS_XR_PAGE_TITLE CR-292 : @T6G_MB_LIB.T6G(SCH_1):PAGE292
J 0
(-7890 5250);
DISPLAY 0.638298 (-7890 5250);
PAINT PINK (-7890 5250);
DISPLAY INVISIBLE (-7890 5250);
FORCEPROP 2 LAST CUSTOM_TXT_CDS <XR_PAGE_TITLE>
J 0
(-7890 5250);
DISPLAY 0.638298 (-7890 5250);
PAINT PINK (-7890 5250);
DISPLAY INVISIBLE (-7890 5250);
FORCEPROP 1 LAST COMMENT_BODY TRUE
J 0
(12 -13);
DISPLAY 0.978723 (12 -13);
PAINT GREEN (12 -13);
DISPLAY INVISIBLE (12 -13);
FORCEPROP 1 LAST Q_DEPT BU9
J 1
(-3763 49);
DISPLAY 1.957447 (-3763 49);
PAINT GREEN (-3763 49);
DISPLAY INVISIBLE (-3763 49);
FORCEPROP 0 LAST CDS_CON_LAST_MODIFIED Thu Aug 24 10:16:17 2023
J 0
(-1885 15);
DISPLAY INVISIBLE (-1885 15);
QUIT
